(kicad_pcb
	(version 20260206)
	(generator "pcbnew")
	(generator_version "10.0")
	(general
		(thickness 1.6)
		(legacy_teardrops no)
	)
	(paper "A4")
	(title_block
		(title "01162023_DA0F0TEBIF0_F0T_Expander_BD_F_brd_V02_OCP.brd")
		(comment 1 "Grand Teton / footprints 5979-5984 of 9728")
	)
	(layers
		(0 "F.Cu" signal "TOP")
		(4 "In1.Cu" signal "GND")
		(6 "In2.Cu" signal "VCC")
		(8 "In3.Cu" signal "VCC1")
		(10 "In4.Cu" signal "GND1")
		(12 "In5.Cu" signal "IN1")
		(14 "In6.Cu" signal "GND2")
		(16 "In7.Cu" signal "IN2")
		(18 "In8.Cu" signal "GND3")
		(20 "In9.Cu" signal "IN3")
		(22 "In10.Cu" signal "GND4")
		(24 "In11.Cu" signal "IN4")
		(26 "In12.Cu" signal "GND5")
		(28 "In13.Cu" signal "IN5")
		(30 "In14.Cu" signal "GND6")
		(32 "In15.Cu" signal "IN6")
		(34 "In16.Cu" signal "GND7")
		(2 "B.Cu" signal "BOTTOM")
		(9 "F.Adhes" user "F.Adhesive")
		(11 "B.Adhes" user "B.Adhesive")
		(13 "F.Paste" user "Package Geometry/Pastemask Top")
		(15 "B.Paste" user "Package Geometry/Pastemask Bottom")
		(5 "F.SilkS" user "Ref Des/Silkscreen Top")
		(7 "B.SilkS" user "Ref Des/Silkscreen Bottom")
		(1 "F.Mask" user "Board Geometry/Soldermask Top")
		(3 "B.Mask" user "Board Geometry/Soldermask Bottom")
		(17 "Dwgs.User" user "User.Drawings")
		(19 "Cmts.User" user "User.Comments")
		(21 "Eco1.User" user "User.Eco1")
		(23 "Eco2.User" user "User.Eco2")
		(25 "Edge.Cuts" user "Board Geometry/Outline")
		(27 "Margin" user)
		(31 "F.CrtYd" user "Package Geometry/Place Bound Top")
		(29 "B.CrtYd" user "Package Geometry/Place Bound Bottom")
		(35 "F.Fab" user "Ref Des/Assembly Top")
		(33 "B.Fab" user "Ref Des/Assembly Bottom")
	)
	(footprint ""
		(layer "F.Cu")
		(at 380.875794 -36.915598 -90)
		(property "Reference" "R5574"
			(at 0 0 270)
			(layer "F.SilkS")
			(hide yes)
			(effects
				(font
					(size 1.27 1.27)
				)
			)
		)
		(property "Value" ""
			(at 0 0 270)
			(layer "F.Fab")
			(effects
				(font
					(size 1.27 1.27)
				)
			)
		)
		(duplicate_pad_numbers_are_jumpers no)
		(fp_line
			(start -0.7874 0.4064)
			(end -0.7874 -0.4064)
			(stroke
				(width 0.1524)
				(type default)
			)
			(layer "F.SilkS")
		)
		(fp_line
			(start 0.7874 0.4064)
			(end -0.7874 0.4064)
			(stroke
				(width 0.1524)
				(type default)
			)
			(layer "F.SilkS")
		)
		(fp_line
			(start -0.7874 -0.4064)
			(end 0.7874 -0.4064)
			(stroke
				(width 0.1524)
				(type default)
			)
			(layer "F.SilkS")
		)
		(fp_line
			(start 0.7874 -0.4064)
			(end 0.7874 0.4064)
			(stroke
				(width 0.1524)
				(type default)
			)
			(layer "F.SilkS")
		)
		(fp_line
			(start -0.67945 0.3048)
			(end -0.67945 -0.305054)
			(stroke
				(width 0.1)
				(type default)
			)
			(layer "F.Fab")
		)
		(fp_line
			(start -0.12065 0.3048)
			(end -0.67945 0.3048)
			(stroke
				(width 0.1)
				(type default)
			)
			(layer "F.Fab")
		)
		(fp_line
			(start 0.120396 0.3048)
			(end 0.120396 0.2794)
			(stroke
				(width 0.1)
				(type default)
			)
			(layer "F.Fab")
		)
		(fp_line
			(start 0.67945 0.3048)
			(end 0.120396 0.3048)
			(stroke
				(width 0.1)
				(type default)
			)
			(layer "F.Fab")
		)
		(fp_line
			(start -0.12065 0.2794)
			(end -0.12065 0.3048)
			(stroke
				(width 0.1)
				(type default)
			)
			(layer "F.Fab")
		)
		(fp_line
			(start 0.120396 0.2794)
			(end -0.12065 0.2794)
			(stroke
				(width 0.1)
				(type default)
			)
			(layer "F.Fab")
		)
		(fp_line
			(start -0.12065 -0.2794)
			(end 0.12065 -0.2794)
			(stroke
				(width 0.1)
				(type default)
			)
			(layer "F.Fab")
		)
		(fp_line
			(start 0.12065 -0.2794)
			(end 0.12065 -0.3048)
			(stroke
				(width 0.1)
				(type default)
			)
			(layer "F.Fab")
		)
		(fp_line
			(start 0.12065 -0.3048)
			(end 0.67945 -0.3048)
			(stroke
				(width 0.1)
				(type default)
			)
			(layer "F.Fab")
		)
		(fp_line
			(start 0.67945 -0.3048)
			(end 0.67945 0.3048)
			(stroke
				(width 0.1)
				(type default)
			)
			(layer "F.Fab")
		)
		(fp_line
			(start -0.67945 -0.305054)
			(end -0.12065 -0.305054)
			(stroke
				(width 0.1)
				(type default)
			)
			(layer "F.Fab")
		)
		(fp_line
			(start -0.12065 -0.305054)
			(end -0.12065 -0.2794)
			(stroke
				(width 0.1)
				(type default)
			)
			(layer "F.Fab")
		)
		(pad "1" smd circle
			(at -0.40005 0 270)
			(size 0 0)
			(layers "F.Cu" "F.Mask" "F.Paste")
			(net "PRSNT_SSD13_R1_N")
		)
		(pad "2" smd circle
			(at 0.40005 0 270)
			(size 0 0)
			(layers "F.Cu" "F.Mask" "F.Paste")
			(net "PRSNT_SSD13_R_N")
		)
	)
	(footprint ""
		(layer "F.Cu")
		(at 136.614662 -66.32194 90)
		(property "Reference" "R5970"
			(at 0 0 90)
			(layer "F.SilkS")
			(hide yes)
			(effects
				(font
					(size 1.27 1.27)
				)
			)
		)
		(property "Value" ""
			(at 0 0 90)
			(layer "F.Fab")
			(effects
				(font
					(size 1.27 1.27)
				)
			)
		)
		(duplicate_pad_numbers_are_jumpers no)
		(fp_line
			(start 0.7874 -0.4064)
			(end 0.7874 0.4064)
			(stroke
				(width 0.1524)
				(type default)
			)
			(layer "F.SilkS")
		)
		(fp_line
			(start -0.7874 -0.4064)
			(end 0.7874 -0.4064)
			(stroke
				(width 0.1524)
				(type default)
			)
			(layer "F.SilkS")
		)
		(fp_line
			(start 0.7874 0.4064)
			(end -0.7874 0.4064)
			(stroke
				(width 0.1524)
				(type default)
			)
			(layer "F.SilkS")
		)
		(fp_line
			(start -0.7874 0.4064)
			(end -0.7874 -0.4064)
			(stroke
				(width 0.1524)
				(type default)
			)
			(layer "F.SilkS")
		)
		(fp_line
			(start -0.12065 -0.305054)
			(end -0.12065 -0.2794)
			(stroke
				(width 0.1)
				(type default)
			)
			(layer "F.Fab")
		)
		(fp_line
			(start -0.67945 -0.305054)
			(end -0.12065 -0.305054)
			(stroke
				(width 0.1)
				(type default)
			)
			(layer "F.Fab")
		)
		(fp_line
			(start 0.67945 -0.3048)
			(end 0.67945 0.3048)
			(stroke
				(width 0.1)
				(type default)
			)
			(layer "F.Fab")
		)
		(fp_line
			(start 0.12065 -0.3048)
			(end 0.67945 -0.3048)
			(stroke
				(width 0.1)
				(type default)
			)
			(layer "F.Fab")
		)
		(fp_line
			(start 0.12065 -0.2794)
			(end 0.12065 -0.3048)
			(stroke
				(width 0.1)
				(type default)
			)
			(layer "F.Fab")
		)
		(fp_line
			(start -0.12065 -0.2794)
			(end 0.12065 -0.2794)
			(stroke
				(width 0.1)
				(type default)
			)
			(layer "F.Fab")
		)
		(fp_line
			(start 0.120396 0.2794)
			(end -0.12065 0.2794)
			(stroke
				(width 0.1)
				(type default)
			)
			(layer "F.Fab")
		)
		(fp_line
			(start -0.12065 0.2794)
			(end -0.12065 0.3048)
			(stroke
				(width 0.1)
				(type default)
			)
			(layer "F.Fab")
		)
		(fp_line
			(start 0.67945 0.3048)
			(end 0.120396 0.3048)
			(stroke
				(width 0.1)
				(type default)
			)
			(layer "F.Fab")
		)
		(fp_line
			(start 0.120396 0.3048)
			(end 0.120396 0.2794)
			(stroke
				(width 0.1)
				(type default)
			)
			(layer "F.Fab")
		)
		(fp_line
			(start -0.12065 0.3048)
			(end -0.67945 0.3048)
			(stroke
				(width 0.1)
				(type default)
			)
			(layer "F.Fab")
		)
		(fp_line
			(start -0.67945 0.3048)
			(end -0.67945 -0.305054)
			(stroke
				(width 0.1)
				(type default)
			)
			(layer "F.Fab")
		)
		(pad "1" smd circle
			(at -0.40005 0 90)
			(size 0 0)
			(layers "F.Cu" "F.Mask" "F.Paste")
			(net "SSD4_PWR_EN_R")
		)
		(pad "2" smd circle
			(at 0.40005 0 90)
			(size 0 0)
			(layers "F.Cu" "F.Mask" "F.Paste")
			(net "P12V_SSD4_CO_EN")
		)
	)
	(footprint ""
		(layer "F.Cu")
		(at 101.774244 -10.534142 -90)
		(property "Reference" "R1652"
			(at 0 0 270)
			(layer "F.SilkS")
			(hide yes)
			(effects
				(font
					(size 1.27 1.27)
				)
			)
		)
		(property "Value" ""
			(at 0 0 270)
			(layer "F.Fab")
			(effects
				(font
					(size 1.27 1.27)
				)
			)
		)
		(duplicate_pad_numbers_are_jumpers no)
		(fp_line
			(start -0.7874 0.4064)
			(end -0.7874 -0.4064)
			(stroke
				(width 0.1524)
				(type default)
			)
			(layer "F.SilkS")
		)
		(fp_line
			(start 0.7874 0.4064)
			(end -0.7874 0.4064)
			(stroke
				(width 0.1524)
				(type default)
			)
			(layer "F.SilkS")
		)
		(fp_line
			(start -0.7874 -0.4064)
			(end 0.7874 -0.4064)
			(stroke
				(width 0.1524)
				(type default)
			)
			(layer "F.SilkS")
		)
		(fp_line
			(start 0.7874 -0.4064)
			(end 0.7874 0.4064)
			(stroke
				(width 0.1524)
				(type default)
			)
			(layer "F.SilkS")
		)
		(fp_line
			(start -0.67945 0.3048)
			(end -0.67945 -0.305054)
			(stroke
				(width 0.1)
				(type default)
			)
			(layer "F.Fab")
		)
		(fp_line
			(start -0.12065 0.3048)
			(end -0.67945 0.3048)
			(stroke
				(width 0.1)
				(type default)
			)
			(layer "F.Fab")
		)
		(fp_line
			(start 0.120396 0.3048)
			(end 0.120396 0.2794)
			(stroke
				(width 0.1)
				(type default)
			)
			(layer "F.Fab")
		)
		(fp_line
			(start 0.67945 0.3048)
			(end 0.120396 0.3048)
			(stroke
				(width 0.1)
				(type default)
			)
			(layer "F.Fab")
		)
		(fp_line
			(start -0.12065 0.2794)
			(end -0.12065 0.3048)
			(stroke
				(width 0.1)
				(type default)
			)
			(layer "F.Fab")
		)
		(fp_line
			(start 0.120396 0.2794)
			(end -0.12065 0.2794)
			(stroke
				(width 0.1)
				(type default)
			)
			(layer "F.Fab")
		)
		(fp_line
			(start -0.12065 -0.2794)
			(end 0.12065 -0.2794)
			(stroke
				(width 0.1)
				(type default)
			)
			(layer "F.Fab")
		)
		(fp_line
			(start 0.12065 -0.2794)
			(end 0.12065 -0.3048)
			(stroke
				(width 0.1)
				(type default)
			)
			(layer "F.Fab")
		)
		(fp_line
			(start 0.12065 -0.3048)
			(end 0.67945 -0.3048)
			(stroke
				(width 0.1)
				(type default)
			)
			(layer "F.Fab")
		)
		(fp_line
			(start 0.67945 -0.3048)
			(end 0.67945 0.3048)
			(stroke
				(width 0.1)
				(type default)
			)
			(layer "F.Fab")
		)
		(fp_line
			(start -0.67945 -0.305054)
			(end -0.12065 -0.305054)
			(stroke
				(width 0.1)
				(type default)
			)
			(layer "F.Fab")
		)
		(fp_line
			(start -0.12065 -0.305054)
			(end -0.12065 -0.2794)
			(stroke
				(width 0.1)
				(type default)
			)
			(layer "F.Fab")
		)
		(pad "1" smd circle
			(at -0.40005 0 270)
			(size 0 0)
			(layers "F.Cu" "F.Mask" "F.Paste")
			(net "SMB_ISO_SSD3_R_SCL")
		)
		(pad "2" smd circle
			(at 0.40005 0 270)
			(size 0 0)
			(layers "F.Cu" "F.Mask" "F.Paste")
			(net "SMB_ISO_SSD3_SCL")
		)
	)
	(footprint ""
		(layer "F.Cu")
		(at 48.820578 -70.307454 90)
		(property "Reference" "PC649"
			(at 0 0 90)
			(layer "F.SilkS")
			(hide yes)
			(effects
				(font
					(size 1.27 1.27)
				)
			)
		)
		(property "Value" ""
			(at 0 0 90)
			(layer "F.Fab")
			(effects
				(font
					(size 1.27 1.27)
				)
			)
		)
		(duplicate_pad_numbers_are_jumpers no)
		(fp_line
			(start 0.7874 -0.4064)
			(end 0.7874 0.4064)
			(stroke
				(width 0.1524)
				(type default)
			)
			(layer "F.SilkS")
		)
		(fp_line
			(start -0.7874 -0.4064)
			(end 0.7874 -0.4064)
			(stroke
				(width 0.1524)
				(type default)
			)
			(layer "F.SilkS")
		)
		(fp_line
			(start 0.7874 0.4064)
			(end -0.7874 0.4064)
			(stroke
				(width 0.1524)
				(type default)
			)
			(layer "F.SilkS")
		)
		(fp_line
			(start -0.7874 0.4064)
			(end -0.7874 -0.4064)
			(stroke
				(width 0.1524)
				(type default)
			)
			(layer "F.SilkS")
		)
		(fp_line
			(start -0.12065 -0.305054)
			(end -0.12065 -0.2794)
			(stroke
				(width 0.1)
				(type default)
			)
			(layer "F.Fab")
		)
		(fp_line
			(start -0.67945 -0.305054)
			(end -0.12065 -0.305054)
			(stroke
				(width 0.1)
				(type default)
			)
			(layer "F.Fab")
		)
		(fp_line
			(start 0.67945 -0.3048)
			(end 0.67945 0.3048)
			(stroke
				(width 0.1)
				(type default)
			)
			(layer "F.Fab")
		)
		(fp_line
			(start 0.12065 -0.3048)
			(end 0.67945 -0.3048)
			(stroke
				(width 0.1)
				(type default)
			)
			(layer "F.Fab")
		)
		(fp_line
			(start 0.12065 -0.2794)
			(end 0.12065 -0.3048)
			(stroke
				(width 0.1)
				(type default)
			)
			(layer "F.Fab")
		)
		(fp_line
			(start -0.12065 -0.2794)
			(end 0.12065 -0.2794)
			(stroke
				(width 0.1)
				(type default)
			)
			(layer "F.Fab")
		)
		(fp_line
			(start 0.120396 0.2794)
			(end -0.12065 0.2794)
			(stroke
				(width 0.1)
				(type default)
			)
			(layer "F.Fab")
		)
		(fp_line
			(start -0.12065 0.2794)
			(end -0.12065 0.3048)
			(stroke
				(width 0.1)
				(type default)
			)
			(layer "F.Fab")
		)
		(fp_line
			(start 0.67945 0.3048)
			(end 0.120396 0.3048)
			(stroke
				(width 0.1)
				(type default)
			)
			(layer "F.Fab")
		)
		(fp_line
			(start 0.120396 0.3048)
			(end 0.120396 0.2794)
			(stroke
				(width 0.1)
				(type default)
			)
			(layer "F.Fab")
		)
		(fp_line
			(start -0.12065 0.3048)
			(end -0.67945 0.3048)
			(stroke
				(width 0.1)
				(type default)
			)
			(layer "F.Fab")
		)
		(fp_line
			(start -0.67945 0.3048)
			(end -0.67945 -0.305054)
			(stroke
				(width 0.1)
				(type default)
			)
			(layer "F.Fab")
		)
		(pad "1" smd circle
			(at -0.40005 0 90)
			(size 0 0)
			(layers "F.Cu" "F.Mask" "F.Paste")
			(net "P12V_AUX")
		)
		(pad "2" smd circle
			(at 0.40005 0 90)
			(size 0 0)
			(layers "F.Cu" "F.Mask" "F.Paste")
			(net "GND")
		)
	)
	(footprint ""
		(layer "F.Cu")
		(at 235.127038 -369.779804 90)
		(property "Reference" "PC14"
			(at 0 0 90)
			(layer "F.SilkS")
			(hide yes)
			(effects
				(font
					(size 1.27 1.27)
				)
			)
		)
		(property "Value" ""
			(at 0 0 90)
			(layer "F.Fab")
			(effects
				(font
					(size 1.27 1.27)
				)
			)
		)
		(duplicate_pad_numbers_are_jumpers no)
		(fp_line
			(start 0.7874 -0.4064)
			(end 0.7874 0.4064)
			(stroke
				(width 0.1524)
				(type default)
			)
			(layer "F.SilkS")
		)
		(fp_line
			(start -0.7874 -0.4064)
			(end 0.7874 -0.4064)
			(stroke
				(width 0.1524)
				(type default)
			)
			(layer "F.SilkS")
		)
		(fp_line
			(start 0.7874 0.4064)
			(end -0.7874 0.4064)
			(stroke
				(width 0.1524)
				(type default)
			)
			(layer "F.SilkS")
		)
		(fp_line
			(start -0.7874 0.4064)
			(end -0.7874 -0.4064)
			(stroke
				(width 0.1524)
				(type default)
			)
			(layer "F.SilkS")
		)
		(fp_line
			(start -0.12065 -0.305054)
			(end -0.12065 -0.2794)
			(stroke
				(width 0.1)
				(type default)
			)
			(layer "F.Fab")
		)
		(fp_line
			(start -0.67945 -0.305054)
			(end -0.12065 -0.305054)
			(stroke
				(width 0.1)
				(type default)
			)
			(layer "F.Fab")
		)
		(fp_line
			(start 0.67945 -0.3048)
			(end 0.67945 0.3048)
			(stroke
				(width 0.1)
				(type default)
			)
			(layer "F.Fab")
		)
		(fp_line
			(start 0.12065 -0.3048)
			(end 0.67945 -0.3048)
			(stroke
				(width 0.1)
				(type default)
			)
			(layer "F.Fab")
		)
		(fp_line
			(start 0.12065 -0.2794)
			(end 0.12065 -0.3048)
			(stroke
				(width 0.1)
				(type default)
			)
			(layer "F.Fab")
		)
		(fp_line
			(start -0.12065 -0.2794)
			(end 0.12065 -0.2794)
			(stroke
				(width 0.1)
				(type default)
			)
			(layer "F.Fab")
		)
		(fp_line
			(start 0.120396 0.2794)
			(end -0.12065 0.2794)
			(stroke
				(width 0.1)
				(type default)
			)
			(layer "F.Fab")
		)
		(fp_line
			(start -0.12065 0.2794)
			(end -0.12065 0.3048)
			(stroke
				(width 0.1)
				(type default)
			)
			(layer "F.Fab")
		)
		(fp_line
			(start 0.67945 0.3048)
			(end 0.120396 0.3048)
			(stroke
				(width 0.1)
				(type default)
			)
			(layer "F.Fab")
		)
		(fp_line
			(start 0.120396 0.3048)
			(end 0.120396 0.2794)
			(stroke
				(width 0.1)
				(type default)
			)
			(layer "F.Fab")
		)
		(fp_line
			(start -0.12065 0.3048)
			(end -0.67945 0.3048)
			(stroke
				(width 0.1)
				(type default)
			)
			(layer "F.Fab")
		)
		(fp_line
			(start -0.67945 0.3048)
			(end -0.67945 -0.305054)
			(stroke
				(width 0.1)
				(type default)
			)
			(layer "F.Fab")
		)
		(pad "1" smd circle
			(at -0.40005 0 90)
			(size 0 0)
			(layers "F.Cu" "F.Mask" "F.Paste")
			(net "HSC_ON")
		)
		(pad "2" smd circle
			(at 0.40005 0 90)
			(size 0 0)
			(layers "F.Cu" "F.Mask" "F.Paste")
			(net "AGND_HSC")
		)
	)
	(footprint ""
		(layer "F.Cu")
		(at 284.224984 -14.735302 180)
		(property "Reference" "C2730"
			(at 0 0 180)
			(layer "F.SilkS")
			(hide yes)
			(effects
				(font
					(size 1.27 1.27)
				)
			)
		)
		(property "Value" ""
			(at 0 0 180)
			(layer "F.Fab")
			(effects
				(font
					(size 1.27 1.27)
				)
			)
		)
		(duplicate_pad_numbers_are_jumpers no)
		(fp_line
			(start 0.7874 0.4064)
			(end -0.7874 0.4064)
			(stroke
				(width 0.1524)
				(type default)
			)
			(layer "F.SilkS")
		)
		(fp_line
			(start 0.7874 -0.4064)
			(end 0.7874 0.4064)
			(stroke
				(width 0.1524)
				(type default)
			)
			(layer "F.SilkS")
		)
		(fp_line
			(start -0.7874 0.4064)
			(end -0.7874 -0.4064)
			(stroke
				(width 0.1524)
				(type default)
			)
			(layer "F.SilkS")
		)
		(fp_line
			(start -0.7874 -0.4064)
			(end 0.7874 -0.4064)
			(stroke
				(width 0.1524)
				(type default)
			)
			(layer "F.SilkS")
		)
		(fp_line
			(start 0.67945 0.3048)
			(end 0.120396 0.3048)
			(stroke
				(width 0.1)
				(type default)
			)
			(layer "F.Fab")
		)
		(fp_line
			(start 0.67945 -0.3048)
			(end 0.67945 0.3048)
			(stroke
				(width 0.1)
				(type default)
			)
			(layer "F.Fab")
		)
		(fp_line
			(start 0.12065 -0.2794)
			(end 0.12065 -0.3048)
			(stroke
				(width 0.1)
				(type default)
			)
			(layer "F.Fab")
		)
		(fp_line
			(start 0.12065 -0.3048)
			(end 0.67945 -0.3048)
			(stroke
				(width 0.1)
				(type default)
			)
			(layer "F.Fab")
		)
		(fp_line
			(start 0.120396 0.3048)
			(end 0.120396 0.2794)
			(stroke
				(width 0.1)
				(type default)
			)
			(layer "F.Fab")
		)
		(fp_line
			(start 0.120396 0.2794)
			(end -0.12065 0.2794)
			(stroke
				(width 0.1)
				(type default)
			)
			(layer "F.Fab")
		)
		(fp_line
			(start -0.12065 0.3048)
			(end -0.67945 0.3048)
			(stroke
				(width 0.1)
				(type default)
			)
			(layer "F.Fab")
		)
		(fp_line
			(start -0.12065 0.2794)
			(end -0.12065 0.3048)
			(stroke
				(width 0.1)
				(type default)
			)
			(layer "F.Fab")
		)
		(fp_line
			(start -0.12065 -0.2794)
			(end 0.12065 -0.2794)
			(stroke
				(width 0.1)
				(type default)
			)
			(layer "F.Fab")
		)
		(fp_line
			(start -0.12065 -0.305054)
			(end -0.12065 -0.2794)
			(stroke
				(width 0.1)
				(type default)
			)
			(layer "F.Fab")
		)
		(fp_line
			(start -0.67945 0.3048)
			(end -0.67945 -0.305054)
			(stroke
				(width 0.1)
				(type default)
			)
			(layer "F.Fab")
		)
		(fp_line
			(start -0.67945 -0.305054)
			(end -0.12065 -0.305054)
			(stroke
				(width 0.1)
				(type default)
			)
			(layer "F.Fab")
		)
		(pad "1" smd circle
			(at -0.40005 0 180)
			(size 0 0)
			(layers "F.Cu" "F.Mask" "F.Paste")
			(net "GND")
		)
		(pad "2" smd circle
			(at 0.40005 0 180)
			(size 0 0)
			(layers "F.Cu" "F.Mask" "F.Paste")
			(net "P3V3_SSD9")
		)
	)
)
